(kicad_pcb
	(version 20241229)
	(generator "pcbnew")
	(generator_version "9.0")
	(general
		(thickness 1.61)
		(legacy_teardrops no)
	)
	(paper "A3")
	(title_block
		(title "SO-DIMM DDR5 Tester")
		(date "2025-11-26")
		(rev "1.3.0")
		(comment 9 "footprints 15-20 of 627")
	)
	(layers
		(0 "F.Cu" signal)
		(4 "In1.Cu" power)
		(6 "In2.Cu" mixed)
		(8 "In3.Cu" power)
		(10 "In4.Cu" mixed)
		(12 "In5.Cu" power)
		(14 "In6.Cu" mixed)
		(16 "In7.Cu" power)
		(18 "In8.Cu" power)
		(20 "In9.Cu" mixed)
		(22 "In10.Cu" power)
		(2 "B.Cu" signal)
		(9 "F.Adhes" user "F.Adhesive")
		(11 "B.Adhes" user "B.Adhesive")
		(13 "F.Paste" user)
		(15 "B.Paste" user)
		(5 "F.SilkS" user "F.Silkscreen")
		(7 "B.SilkS" user "B.Silkscreen")
		(1 "F.Mask" user)
		(3 "B.Mask" user)
		(17 "Dwgs.User" user "User.Drawings")
		(19 "Cmts.User" user "User.Comments")
		(21 "Eco1.User" user "User.Eco1")
		(23 "Eco2.User" user "User.Eco2")
		(25 "Edge.Cuts" user)
		(27 "Margin" user)
		(31 "F.CrtYd" user "F.Courtyard")
		(29 "B.CrtYd" user "B.Courtyard")
		(35 "F.Fab" user)
		(33 "B.Fab" user)
	)
	(footprint "antmicro-footprints:C_0402_1005Metric"
		(layer "F.Cu")
		(at 105.467344 177.267328)
		(descr "Capacitor SMD 0402")
		(tags "capacitor SMD 0402")
		(property "Reference" "C122"
			(at 0 -0.699 0)
			(layer "F.SilkS")
			(hide yes)
			(effects
				(font
					(size 0.7 0.7)
					(thickness 0.15)
				)
				(justify left bottom)
			)
		)
		(property "Value" "C_4u7_0402"
			(at -1.022927 2.155213 0)
			(layer "F.Fab")
			(effects
				(font
					(size 0.7 0.7)
					(thickness 0.15)
				)
				(justify left bottom)
			)
		)
		(property "Datasheet" "https://www.murata.com/products/productdetail?partno=GRM155R61A475MEAA%23"
			(at 0 0 0)
			(layer "F.Fab")
			(hide yes)
			(effects
				(font
					(size 1.27 1.27)
					(thickness 0.15)
				)
			)
		)
		(property "Author" "Antmicro"
			(at 0 0 0)
			(layer "F.Fab")
			(hide yes)
			(effects
				(font
					(size 1 1)
					(thickness 0.15)
				)
			)
		)
		(property "Dielectric" ""
			(at 0 0 0)
			(layer "F.Fab")
			(hide yes)
			(effects
				(font
					(size 1 1)
					(thickness 0.15)
				)
			)
		)
		(property "License" "Apache-2.0"
			(at 0 0 0)
			(layer "F.Fab")
			(hide yes)
			(effects
				(font
					(size 1 1)
					(thickness 0.15)
				)
			)
		)
		(property "MPN" "GRM155R61A475MEAAD"
			(at 0 0 0)
			(layer "F.Fab")
			(hide yes)
			(effects
				(font
					(size 1 1)
					(thickness 0.15)
				)
			)
		)
		(property "Manufacturer" "Murata"
			(at 0 0 0)
			(layer "F.Fab")
			(hide yes)
			(effects
				(font
					(size 1 1)
					(thickness 0.15)
				)
			)
		)
		(property "Val" "4u7"
			(at 0 0 0)
			(layer "F.Fab")
			(hide yes)
			(effects
				(font
					(size 1 1)
					(thickness 0.15)
				)
			)
		)
		(property "Voltage" ""
			(at 0 0 0)
			(layer "F.Fab")
			(hide yes)
			(effects
				(font
					(size 1 1)
					(thickness 0.15)
				)
			)
		)
		(sheetname "/Debug FTDI/")
		(sheetfile "debug-ftdi.kicad_sch")
		(attr smd)
		(fp_rect
			(start -0.9659 -0.481258)
			(end 0.9649 0.458742)
			(stroke
				(width 0.05)
				(type solid)
			)
			(fill no)
			(layer "F.CrtYd")
		)
		(fp_line
			(start -0.499 -0.25)
			(end 0.499 -0.25)
			(stroke
				(width 0.15)
				(type solid)
			)
			(layer "F.Fab")
		)
		(fp_line
			(start -0.499 0.248)
			(end -0.499 -0.25)
			(stroke
				(width 0.15)
				(type solid)
			)
			(layer "F.Fab")
		)
		(fp_line
			(start 0.499 -0.25)
			(end 0.499 0.248)
			(stroke
				(width 0.15)
				(type solid)
			)
			(layer "F.Fab")
		)
		(fp_line
			(start 0.499 0.248)
			(end -0.499 0.248)
			(stroke
				(width 0.15)
				(type solid)
			)
			(layer "F.Fab")
		)
		(pad "1" smd roundrect
			(at -0.484 0)
			(size 0.59 0.64)
			(layers "F.Cu" "F.Mask" "F.Paste")
			(roundrect_rratio 0.25)
			(net 8 "/Debug FTDI/FTDI_VCORE")
			(pintype "passive")
		)
		(pad "2" smd roundrect
			(at 0.484 0)
			(size 0.59 0.64)
			(layers "F.Cu" "F.Mask" "F.Paste")
			(roundrect_rratio 0.25)
			(net 1 "GND")
			(pintype "passive")
		)
	)
	(footprint "antmicro-footprints:FB_0603_1608Metric"
		(layer "F.Cu")
		(at 89.310501 171.035 -90)
		(property "Reference" "FB2"
			(at 0 -0.8 270)
			(layer "F.SilkS")
			(hide yes)
			(effects
				(font
					(size 0.7 0.7)
					(thickness 0.15)
				)
				(justify left bottom)
			)
		)
		(property "Value" "FB_600Z_0.5A_Murata-BLM18AG_0603"
			(at 0 1.5 270)
			(layer "F.Fab")
			(effects
				(font
					(size 0.7 0.7)
					(thickness 0.15)
				)
				(justify left bottom)
			)
		)
		(property "Datasheet" "https://www.murata.com/en-us/products/productdata/8796738650142/ENFA0003.pdf"
			(at 0 0 270)
			(layer "F.Fab")
			(hide yes)
			(effects
				(font
					(size 1.27 1.27)
					(thickness 0.15)
				)
			)
		)
		(property "Author" "Antmicro"
			(at -81.724499 260.345501 0)
			(layer "F.Fab")
			(hide yes)
			(effects
				(font
					(size 1 1)
					(thickness 0.15)
				)
			)
		)
		(property "License" "Apache-2.0"
			(at -81.724499 260.345501 0)
			(layer "F.Fab")
			(hide yes)
			(effects
				(font
					(size 1 1)
					(thickness 0.15)
				)
			)
		)
		(property "MPN" "BLM18AG601SN1D"
			(at -81.724499 260.345501 0)
			(layer "F.Fab")
			(hide yes)
			(effects
				(font
					(size 1 1)
					(thickness 0.15)
				)
			)
		)
		(property "Manufacturer" "Murata"
			(at -81.724499 260.345501 0)
			(layer "F.Fab")
			(hide yes)
			(effects
				(font
					(size 1 1)
					(thickness 0.15)
				)
			)
		)
		(property "Val" "600Z/0.5A"
			(at -81.724499 260.345501 0)
			(layer "F.Fab")
			(hide yes)
			(effects
				(font
					(size 1 1)
					(thickness 0.15)
				)
			)
		)
		(sheetname "/Debug FTDI/")
		(sheetfile "debug-ftdi.kicad_sch")
		(attr smd)
		(fp_line
			(start -0.196 0.406)
			(end 0.193 0.406)
			(stroke
				(width 0.15)
				(type solid)
			)
			(layer "F.SilkS")
		)
		(fp_line
			(start -0.196 -0.408)
			(end 0.193 -0.408)
			(stroke
				(width 0.15)
				(type solid)
			)
			(layer "F.SilkS")
		)
		(fp_rect
			(start -1.3 -0.6)
			(end 1.3 0.6)
			(stroke
				(width 0.05)
				(type solid)
			)
			(fill no)
			(layer "F.CrtYd")
		)
		(fp_line
			(start -0.803 0.406)
			(end -0.803 -0.408)
			(stroke
				(width 0.15)
				(type solid)
			)
			(layer "F.Fab")
		)
		(fp_line
			(start 0.8 0.406)
			(end -0.803 0.406)
			(stroke
				(width 0.15)
				(type solid)
			)
			(layer "F.Fab")
		)
		(fp_line
			(start 0.8 -0.408)
			(end 0.8 0.406)
			(stroke
				(width 0.15)
				(type solid)
			)
			(layer "F.Fab")
		)
		(fp_line
			(start 0.8 -0.408)
			(end -0.803 -0.408)
			(stroke
				(width 0.15)
				(type solid)
			)
			(layer "F.Fab")
		)
		(pad "1" smd roundrect
			(at -0.891 0 270)
			(size 0.762 1.09)
			(layers "F.Cu" "F.Mask" "F.Paste")
			(roundrect_rratio 0.15)
			(net 6 "/Debug FTDI/FTDI_3V3")
			(pintype "passive")
		)
		(pad "2" smd roundrect
			(at 0.888 0 270)
			(size 0.762 1.09)
			(layers "F.Cu" "F.Mask" "F.Paste")
			(roundrect_rratio 0.15)
			(net 5 "/Debug FTDI/FTDI_VPHY")
			(pintype "passive")
		)
	)
	(footprint "antmicro-footprints:R_0402_1005Metric"
		(layer "F.Cu")
		(at 91.052344 173.382328)
		(descr "Resistor SMD 0402")
		(tags "resistor SMD 0402")
		(property "Reference" "R44"
			(at -1.122484 -0.772697 0)
			(layer "F.SilkS")
			(hide yes)
			(effects
				(font
					(size 0.7 0.7)
					(thickness 0.15)
				)
				(justify left bottom)
			)
		)
		(property "Value" "R_12k_0402"
			(at -1.011843 1.772047 0)
			(layer "F.Fab")
			(effects
				(font
					(size 0.7 0.7)
					(thickness 0.15)
				)
				(justify left bottom)
			)
		)
		(property "Datasheet" "https://www.bourns.com/docs/product-datasheets/cr.pdf"
			(at 0 0 0)
			(layer "F.Fab")
			(hide yes)
			(effects
				(font
					(size 1.27 1.27)
					(thickness 0.15)
				)
			)
		)
		(property "Author" "Antmicro"
			(at 0 0 0)
			(layer "F.Fab")
			(hide yes)
			(effects
				(font
					(size 1 1)
					(thickness 0.15)
				)
			)
		)
		(property "License" "Apache-2.0"
			(at 0 0 0)
			(layer "F.Fab")
			(hide yes)
			(effects
				(font
					(size 1 1)
					(thickness 0.15)
				)
			)
		)
		(property "MPN" "CR0402-FX-1202GLF"
			(at 0 0 0)
			(layer "F.Fab")
			(hide yes)
			(effects
				(font
					(size 1 1)
					(thickness 0.15)
				)
			)
		)
		(property "Manufacturer" "Bourns"
			(at 0 0 0)
			(layer "F.Fab")
			(hide yes)
			(effects
				(font
					(size 1 1)
					(thickness 0.15)
				)
			)
		)
		(property "Tolerance" "1%"
			(at 0 0 0)
			(layer "F.Fab")
			(hide yes)
			(effects
				(font
					(size 1 1)
					(thickness 0.15)
				)
			)
		)
		(property "Val" "12k"
			(at 0 0 0)
			(layer "F.Fab")
			(hide yes)
			(effects
				(font
					(size 1 1)
					(thickness 0.15)
				)
			)
		)
		(sheetname "/Debug FTDI/")
		(sheetfile "debug-ftdi.kicad_sch")
		(attr smd)
		(fp_rect
			(start -0.93 -0.47)
			(end 0.93 0.47)
			(stroke
				(width 0.05)
				(type solid)
			)
			(fill no)
			(layer "F.CrtYd")
		)
		(fp_rect
			(start -0.5 -0.25)
			(end 0.5 0.25)
			(stroke
				(width 0.15)
				(type solid)
			)
			(fill no)
			(layer "F.Fab")
		)
		(pad "1" smd roundrect
			(at -0.485 0)
			(size 0.59 0.64)
			(layers "F.Cu" "F.Mask" "F.Paste")
			(roundrect_rratio 0.25)
			(net 1 "GND")
			(pintype "passive")
		)
		(pad "2" smd roundrect
			(at 0.485 0)
			(size 0.59 0.64)
			(layers "F.Cu" "F.Mask" "F.Paste")
			(roundrect_rratio 0.25)
			(net 375 "Net-(U6-REF)")
			(pintype "passive")
		)
	)
	(footprint "antmicro-footprints:C_0402_1005Metric"
		(layer "F.Cu")
		(at 90.690501 176.036 -90)
		(descr "Capacitor SMD 0402")
		(tags "capacitor SMD 0402")
		(property "Reference" "C110"
			(at 0 -0.699 270)
			(layer "F.SilkS")
			(hide yes)
			(effects
				(font
					(size 0.7 0.7)
					(thickness 0.15)
				)
				(justify left bottom)
			)
		)
		(property "Value" "C_100n_0402"
			(at -1.022927 2.155213 270)
			(layer "F.Fab")
			(effects
				(font
					(size 0.7 0.7)
					(thickness 0.15)
				)
				(justify left bottom)
			)
		)
		(property "Datasheet" "https://www.murata.com/products/productdetail?partno=GRM155R61H104KE14%23"
			(at 0 0 270)
			(layer "F.Fab")
			(hide yes)
			(effects
				(font
					(size 1.27 1.27)
					(thickness 0.15)
				)
			)
		)
		(property "Author" "Antmicro"
			(at -85.345499 266.726501 0)
			(layer "F.Fab")
			(hide yes)
			(effects
				(font
					(size 1 1)
					(thickness 0.15)
				)
			)
		)
		(property "Dielectric" "X5R"
			(at -85.345499 266.726501 0)
			(layer "F.Fab")
			(hide yes)
			(effects
				(font
					(size 1 1)
					(thickness 0.15)
				)
			)
		)
		(property "License" "Apache-2.0"
			(at -85.345499 266.726501 0)
			(layer "F.Fab")
			(hide yes)
			(effects
				(font
					(size 1 1)
					(thickness 0.15)
				)
			)
		)
		(property "MPN" "GRM155R61H104KE14D"
			(at -85.345499 266.726501 0)
			(layer "F.Fab")
			(hide yes)
			(effects
				(font
					(size 1 1)
					(thickness 0.15)
				)
			)
		)
		(property "Manufacturer" "Murata"
			(at -85.345499 266.726501 0)
			(layer "F.Fab")
			(hide yes)
			(effects
				(font
					(size 1 1)
					(thickness 0.15)
				)
			)
		)
		(property "Val" "100n"
			(at -85.345499 266.726501 0)
			(layer "F.Fab")
			(hide yes)
			(effects
				(font
					(size 1 1)
					(thickness 0.15)
				)
			)
		)
		(property "Voltage" "50V"
			(at -85.345499 266.726501 0)
			(layer "F.Fab")
			(hide yes)
			(effects
				(font
					(size 1 1)
					(thickness 0.15)
				)
			)
		)
		(sheetname "/Debug FTDI/")
		(sheetfile "debug-ftdi.kicad_sch")
		(attr smd)
		(fp_rect
			(start -0.9659 -0.481258)
			(end 0.9649 0.458742)
			(stroke
				(width 0.05)
				(type solid)
			)
			(fill no)
			(layer "F.CrtYd")
		)
		(fp_line
			(start -0.499 0.248)
			(end -0.499 -0.25)
			(stroke
				(width 0.15)
				(type solid)
			)
			(layer "F.Fab")
		)
		(fp_line
			(start 0.499 0.248)
			(end -0.499 0.248)
			(stroke
				(width 0.15)
				(type solid)
			)
			(layer "F.Fab")
		)
		(fp_line
			(start -0.499 -0.25)
			(end 0.499 -0.25)
			(stroke
				(width 0.15)
				(type solid)
			)
			(layer "F.Fab")
		)
		(fp_line
			(start 0.499 -0.25)
			(end 0.499 0.248)
			(stroke
				(width 0.15)
				(type solid)
			)
			(layer "F.Fab")
		)
		(pad "1" smd roundrect
			(at -0.484 0 270)
			(size 0.59 0.64)
			(layers "F.Cu" "F.Mask" "F.Paste")
			(roundrect_rratio 0.25)
			(net 3 "/Debug FTDI/FTDI_VPLL")
			(pintype "passive")
		)
		(pad "2" smd roundrect
			(at 0.484 0 270)
			(size 0.59 0.64)
			(layers "F.Cu" "F.Mask" "F.Paste")
			(roundrect_rratio 0.25)
			(net 1 "GND")
			(pintype "passive")
		)
	)
	(footprint "antmicro-footprints:C_0402_1005Metric"
		(layer "F.Cu")
		(at 91.689001 176.035 -90)
		(descr "Capacitor SMD 0402")
		(tags "capacitor SMD 0402")
		(property "Reference" "C114"
			(at 0 -0.699 270)
			(layer "F.SilkS")
			(hide yes)
			(effects
				(font
					(size 0.7 0.7)
					(thickness 0.15)
				)
				(justify left bottom)
			)
		)
		(property "Value" "C_4u7_0402"
			(at -1.022927 2.155213 270)
			(layer "F.Fab")
			(effects
				(font
					(size 0.7 0.7)
					(thickness 0.15)
				)
				(justify left bottom)
			)
		)
		(property "Datasheet" "https://www.murata.com/products/productdetail?partno=GRM155R61A475MEAA%23"
			(at 0 0 270)
			(layer "F.Fab")
			(hide yes)
			(effects
				(font
					(size 1.27 1.27)
					(thickness 0.15)
				)
			)
		)
		(property "Author" "Antmicro"
			(at -84.345999 267.724001 0)
			(layer "F.Fab")
			(hide yes)
			(effects
				(font
					(size 1 1)
					(thickness 0.15)
				)
			)
		)
		(property "Dielectric" ""
			(at -84.345999 267.724001 0)
			(layer "F.Fab")
			(hide yes)
			(effects
				(font
					(size 1 1)
					(thickness 0.15)
				)
			)
		)
		(property "License" "Apache-2.0"
			(at -84.345999 267.724001 0)
			(layer "F.Fab")
			(hide yes)
			(effects
				(font
					(size 1 1)
					(thickness 0.15)
				)
			)
		)
		(property "MPN" "GRM155R61A475MEAAD"
			(at -84.345999 267.724001 0)
			(layer "F.Fab")
			(hide yes)
			(effects
				(font
					(size 1 1)
					(thickness 0.15)
				)
			)
		)
		(property "Manufacturer" "Murata"
			(at -84.345999 267.724001 0)
			(layer "F.Fab")
			(hide yes)
			(effects
				(font
					(size 1 1)
					(thickness 0.15)
				)
			)
		)
		(property "Val" "4u7"
			(at -84.345999 267.724001 0)
			(layer "F.Fab")
			(hide yes)
			(effects
				(font
					(size 1 1)
					(thickness 0.15)
				)
			)
		)
		(property "Voltage" ""
			(at -84.345999 267.724001 0)
			(layer "F.Fab")
			(hide yes)
			(effects
				(font
					(size 1 1)
					(thickness 0.15)
				)
			)
		)
		(sheetname "/Debug FTDI/")
		(sheetfile "debug-ftdi.kicad_sch")
		(attr smd)
		(fp_rect
			(start -0.9659 -0.481258)
			(end 0.9649 0.458742)
			(stroke
				(width 0.05)
				(type solid)
			)
			(fill no)
			(layer "F.CrtYd")
		)
		(fp_line
			(start -0.499 0.248)
			(end -0.499 -0.25)
			(stroke
				(width 0.15)
				(type solid)
			)
			(layer "F.Fab")
		)
		(fp_line
			(start 0.499 0.248)
			(end -0.499 0.248)
			(stroke
				(width 0.15)
				(type solid)
			)
			(layer "F.Fab")
		)
		(fp_line
			(start -0.499 -0.25)
			(end 0.499 -0.25)
			(stroke
				(width 0.15)
				(type solid)
			)
			(layer "F.Fab")
		)
		(fp_line
			(start 0.499 -0.25)
			(end 0.499 0.248)
			(stroke
				(width 0.15)
				(type solid)
			)
			(layer "F.Fab")
		)
		(pad "1" smd roundrect
			(at -0.484 0 270)
			(size 0.59 0.64)
			(layers "F.Cu" "F.Mask" "F.Paste")
			(roundrect_rratio 0.25)
			(net 3 "/Debug FTDI/FTDI_VPLL")
			(pintype "passive")
		)
		(pad "2" smd roundrect
			(at 0.484 0 270)
			(size 0.59 0.64)
			(layers "F.Cu" "F.Mask" "F.Paste")
			(roundrect_rratio 0.25)
			(net 1 "GND")
			(pintype "passive")
		)
	)
	(footprint "antmicro-footprints:FB_0603_1608Metric"
		(layer "F.Cu")
		(at 89.310501 176.535 90)
		(property "Reference" "FB1"
			(at 0 -0.8 90)
			(layer "F.SilkS")
			(hide yes)
			(effects
				(font
					(size 0.7 0.7)
					(thickness 0.15)
				)
				(justify left bottom)
			)
		)
		(property "Value" "FB_600Z_0.5A_Murata-BLM18AG_0603"
			(at 0 1.5 90)
			(layer "F.Fab")
			(effects
				(font
					(size 0.7 0.7)
					(thickness 0.15)
				)
				(justify left bottom)
			)
		)
		(property "Datasheet" "https://www.murata.com/en-us/products/productdata/8796738650142/ENFA0003.pdf"
			(at 0 0 90)
			(layer "F.Fab")
			(hide yes)
			(effects
				(font
					(size 1.27 1.27)
					(thickness 0.15)
				)
			)
		)
		(property "Author" "Antmicro"
			(at 265.845501 87.224499 0)
			(layer "F.Fab")
			(hide yes)
			(effects
				(font
					(size 1 1)
					(thickness 0.15)
				)
			)
		)
		(property "License" "Apache-2.0"
			(at 265.845501 87.224499 0)
			(layer "F.Fab")
			(hide yes)
			(effects
				(font
					(size 1 1)
					(thickness 0.15)
				)
			)
		)
		(property "MPN" "BLM18AG601SN1D"
			(at 265.845501 87.224499 0)
			(layer "F.Fab")
			(hide yes)
			(effects
				(font
					(size 1 1)
					(thickness 0.15)
				)
			)
		)
		(property "Manufacturer" "Murata"
			(at 265.845501 87.224499 0)
			(layer "F.Fab")
			(hide yes)
			(effects
				(font
					(size 1 1)
					(thickness 0.15)
				)
			)
		)
		(property "Val" "600Z/0.5A"
			(at 265.845501 87.224499 0)
			(layer "F.Fab")
			(hide yes)
			(effects
				(font
					(size 1 1)
					(thickness 0.15)
				)
			)
		)
		(sheetname "/Debug FTDI/")
		(sheetfile "debug-ftdi.kicad_sch")
		(attr smd)
		(fp_line
			(start -0.196 -0.408)
			(end 0.193 -0.408)
			(stroke
				(width 0.15)
				(type solid)
			)
			(layer "F.SilkS")
		)
		(fp_line
			(start -0.196 0.406)
			(end 0.193 0.406)
			(stroke
				(width 0.15)
				(type solid)
			)
			(layer "F.SilkS")
		)
		(fp_rect
			(start -1.3 -0.6)
			(end 1.3 0.6)
			(stroke
				(width 0.05)
				(type solid)
			)
			(fill no)
			(layer "F.CrtYd")
		)
		(fp_line
			(start 0.8 -0.408)
			(end -0.803 -0.408)
			(stroke
				(width 0.15)
				(type solid)
			)
			(layer "F.Fab")
		)
		(fp_line
			(start 0.8 -0.408)
			(end 0.8 0.406)
			(stroke
				(width 0.15)
				(type solid)
			)
			(layer "F.Fab")
		)
		(fp_line
			(start 0.8 0.406)
			(end -0.803 0.406)
			(stroke
				(width 0.15)
				(type solid)
			)
			(layer "F.Fab")
		)
		(fp_line
			(start -0.803 0.406)
			(end -0.803 -0.408)
			(stroke
				(width 0.15)
				(type solid)
			)
			(layer "F.Fab")
		)
		(pad "1" smd roundrect
			(at -0.891 0 90)
			(size 0.762 1.09)
			(layers "F.Cu" "F.Mask" "F.Paste")
			(roundrect_rratio 0.15)
			(net 6 "/Debug FTDI/FTDI_3V3")
			(pintype "passive")
		)
		(pad "2" smd roundrect
			(at 0.888 0 90)
			(size 0.762 1.09)
			(layers "F.Cu" "F.Mask" "F.Paste")
			(roundrect_rratio 0.15)
			(net 3 "/Debug FTDI/FTDI_VPLL")
			(pintype "passive")
		)
	)
)
